FILE_TYPE = MULTI_PHYS_TABLE;
PART 'CRYSTAL'
{====================================================================================================================================================================================================================================================================}
:VALUE          | PACK_TYPE | MATERIAL | PART_NUMBER     = EnvComp                  |  PART_NUMBER | JEDEC_TYPE | CLASS | DESCRIPTION                                                          | HEIGHT     | COMPONENT_TYPE | LEAD_LENGTH| LPID    | SPEED_URL | Status |RPL| AML | Bus_Unit | Days ;
{====================================================================================================================================================================================================================================================================}
'24.000MHZ'     | 'SM'      | 'IC'     | 'D95126-001'(!) = 'YES;YES;YES;UNK;ok;VLD' | 'D95126-001' | 'SMY4719A' | 'IC'  | 'XTAL,24.000MHZ'                                                     | '0.126 IN' | 'SMTOTHER'     | ''         | '510'   | 'http://speed.intel.com:8081/speed/module/pdm/item/pdm_item_detail_direct.asp?item_cde=D95126-001&item_rev=01&url_param=unused' | 'Preliminary' | 'NO' | '3' | 'SMO_BOARDS' | '???' 
'24.000MHZ'     | 'SM'      | 'EMPTY'  | 'D95126-001'(!) = 'YES;YES;YES;UNK;ok;VLD' | 'D95126-001' | 'SMY4719A' | 'IO'  | 'XTAL,24.000MHZ'                                                     | '0.126 IN' | 'SMTOTHER'     | ''         | '510'   | 'http://speed.intel.com:8081/speed/module/pdm/item/pdm_item_detail_direct.asp?item_cde=D95126-001&item_rev=01&url_param=unused' | 'Preliminary' | 'NO' | '3' | 'SMO_BOARDS' | '???' 
'25.000MHZ'     |'2013LF'   | 'IC'     | 'D71700-033'(!) = 'YES;YES;YES;UNK;ok;YTC' |'D71700-033'  |'SMY1310A'  |'IC'   |'XTAL,CER3.2X2.5,25,20PF,0-85DEG'                                     |'0.031 IN'  |'SMTOTHER'      |''          | '1719'  | 'http://speed.intel.com:8081/speed/module/pdm/item/pdm_item_detail_direct.asp?item_cde=D71700-033&item_rev=01&url_param=unused' | 'Design' | 'YES' | '2' | 'SMO_BOARDS' | '???' 
'25.000MHZ'     |'2013LF'   | 'EMPTY'  | 'D71700-033'(!) = 'YES;YES;YES;UNK;ok;YTC' |'D71700-033'  |'SMY1310A'  |'IO'   |'XTAL,CER3.2X2.5,25,20PF,0-85DEG'                                     |'0.031 IN'  |'SMTOTHER'      |''          | '1719'  | 'http://speed.intel.com:8081/speed/module/pdm/item/pdm_item_detail_direct.asp?item_cde=D71700-033&item_rev=01&url_param=unused' | 'Design' | 'YES' | '2' | 'SMO_BOARDS' | '???' 
'25.000MHZ'     | '2013'    | 'IC'     | 'H19611-001'(!) = 'YES;YES;YES;UNK;ok;VLD' | 'H19611-001' | 'SMY1310A' | 'IC'  | 'XTAL,25.000MHZ,20PF,SM,7M25020008'                                  | '0.031 IN' | 'SMTOTHER'     | ''         | '1719'  |'http://speed.intel.com:8081/speed/module/pdm/item/pdm_item_detail_direct.asp?item_cde=H19611-001&item_rev=01&url_param=unused' | 'Design' | 'NO' | '1' | 'SG' | '???' 
'25.000MHZ'     | '2013'    | 'EMPTY'  | 'H19611-001'(!) = 'YES;YES;YES;UNK;ok;VLD' | 'H19611-001' | 'SMY1310A' | 'IO'  | 'XTAL,25.000MHZ,20PF,SM,7M25020008'                                  | '0.031 IN' | 'SMTOTHER'     | ''         | '1719'  |'http://speed.intel.com:8081/speed/module/pdm/item/pdm_item_detail_direct.asp?item_cde=H19611-001&item_rev=01&url_param=unused' | 'Design' | 'NO' | '1' | 'SG' | '???' 
'48.000MHZ'     | '2013'    | 'IC'     | 'D71700-058'(!) = 'YES;YES;YES;UNK;ok;VLD' | 'D71700-058' | 'SMY1310A' | 'IC'  | 'XTAL,CER3.2X2.5,48.00,MHZ,10.0,PF,0.003%,SM'                        | '0.031 IN' | 'SMTOTHER'     | ''         | '1719'  |'http://speed.intel.com:8081/speed/module/pdm/item/pdm_item_detail_direct.asp?item_cde=D71700-058&item_rev=01&url_param=unused' | 'Design' | 'YES' | '2' | 'SMO_BOARDS' | '???' 
'48.000MHZ'     | '2013'    | 'EMPTY'  | 'D71700-058'(!) = 'YES;YES;YES;UNK;ok;VLD' | 'D71700-058' | 'SMY1310A' | 'IO'  | 'XTAL,CER3.2X2.5,48.00,MHZ,10.0,PF,0.003%,SM'                        | '0.031 IN' | 'SMTOTHER'     | ''         | '1719'  |'http://speed.intel.com:8081/speed/module/pdm/item/pdm_item_detail_direct.asp?item_cde=D71700-058&item_rev=01&url_param=unused' | 'Design' | 'YES' | '2' | 'SMO_BOARDS' | '???' 
'32.768KHZ'     | 'SM'      | 'IC'     | 'C13544-023'(!) = ''                       | 'C13544-023' | 'SMY1306A' | 'IC'  | 'XTAL,CER3.2X1.5,32.768,KHZ,12.5,PF,0.002%,SM'                       | '0.035 IN' | 'SMTOTHER'     | ''         | '1776'  | 'http://speed.intel.com:8081/speed/module/pdm/item/pdm_item_detail_direct.asp?item_cde=C13544-023&item_rev=01&url_param=unused' | '' | '' | '' | '' | '' 
'32.768KHZ'     | 'SM'      | 'EMPTY'  | 'C13544-023'(!) = ''                       | 'C13544-023' | 'SMY1306A' | 'IO'  | 'XTAL,CER3.2X1.5,32.768,KHZ,12.5,PF,0.002%,SM'                       | '0.035 IN' | 'SMTOTHER'     | ''         | '1776'  | 'http://speed.intel.com:8081/speed/module/pdm/item/pdm_item_detail_direct.asp?item_cde=C13544-023&item_rev=01&url_param=unused' | '' | '' | '' | '' | '' 
'25.000MHZ'     | '2013'    | 'IC'     | 'D71700-057'(!) = ''                       | 'D71700-057' | 'SMY1310A' | 'IC'  |'(USE SYM 3 OR 4)XTAL,CER3.2X2.5,25.00,MHZ,18.0,PF,0.003%,SM'         | '0.031 IN' | 'SMTOTHER'     | ''         | '1719'  | 'http://speed.intel.com:8081/speed/module/pdm/item/pdm_item_detail_direct.asp?item_cde=D71700-057&item_rev=01&url_param=unused' | '' | '' | '' | '' | '' 
'25.000MHZ'     | '2013'    | 'EMPTY'  | 'D71700-057'(!) = ''                       | 'D71700-057' | 'SMY1310A' | 'IO'  |'(USE SYM 3 OR 4)XTAL,CER3.2X2.5,25.00,MHZ,18.0,PF,0.003%,SM'         | '0.031 IN' | 'SMTOTHER'     | ''         | '1719'  | 'http://speed.intel.com:8081/speed/module/pdm/item/pdm_item_detail_direct.asp?item_cde=D71700-057&item_rev=01&url_param=unused' | '' | '' | '' | '' | '' 
{EOL PARTS}
END_PART
END.
